(kicad_pcb
	(version 20260206)
	(generator "pcbnew")
	(generator_version "10.0")
	(general
		(thickness 1.6)
		(legacy_teardrops no)
	)
	(paper "A4")
	(title_block
		(title "04192023_DAF0TMB3IC0_F0TG_MB_C_brd_V02_OCP.brd")
		(comment 1 "Grand Teton / footprints 4589-4595 of 8354")
	)
	(layers
		(0 "F.Cu" signal "TOP")
		(4 "In1.Cu" signal "GND")
		(6 "In2.Cu" signal "IN1")
		(8 "In3.Cu" signal "GND1")
		(10 "In4.Cu" signal "IN2")
		(12 "In5.Cu" signal "GND2")
		(14 "In6.Cu" signal "IN3")
		(16 "In7.Cu" signal "GND3")
		(18 "In8.Cu" signal "VCC")
		(20 "In9.Cu" signal "VCC1")
		(22 "In10.Cu" signal "GND4")
		(24 "In11.Cu" signal "IN4")
		(26 "In12.Cu" signal "GND5")
		(28 "In13.Cu" signal "IN5")
		(30 "In14.Cu" signal "GND6")
		(32 "In15.Cu" signal "IN6")
		(34 "In16.Cu" signal "GND7")
		(2 "B.Cu" signal "BOTTOM")
		(9 "F.Adhes" user "F.Adhesive")
		(11 "B.Adhes" user "B.Adhesive")
		(13 "F.Paste" user "Package Geometry/Pastemask Top")
		(15 "B.Paste" user "Package Geometry/Pastemask Bottom")
		(5 "F.SilkS" user "Ref Des/Silkscreen Top")
		(7 "B.SilkS" user "Ref Des/Silkscreen Bottom")
		(1 "F.Mask" user "Board Geometry/Soldermask Top")
		(3 "B.Mask" user "Board Geometry/Soldermask Bottom")
		(17 "Dwgs.User" user "User.Drawings")
		(19 "Cmts.User" user "User.Comments")
		(21 "Eco1.User" user "User.Eco1")
		(23 "Eco2.User" user "User.Eco2")
		(25 "Edge.Cuts" user "Board Geometry/Outline")
		(27 "Margin" user)
		(31 "F.CrtYd" user "Package Geometry/Place Bound Top")
		(29 "B.CrtYd" user "Package Geometry/Place Bound Bottom")
		(35 "F.Fab" user "Ref Des/Assembly Top")
		(33 "B.Fab" user "Ref Des/Assembly Bottom")
	)
	(footprint ""
		(layer "F.Cu")
		(at 90.819478 -148.94941 180)
		(property "Reference" "R154"
			(at 0 0 180)
			(layer "F.SilkS")
			(hide yes)
			(effects
				(font
					(size 1.27 1.27)
				)
			)
		)
		(property "Value" ""
			(at 0 0 180)
			(layer "F.Fab")
			(effects
				(font
					(size 1.27 1.27)
				)
			)
		)
		(duplicate_pad_numbers_are_jumpers no)
		(fp_line
			(start 0.7874 0.4064)
			(end -0.7874 0.4064)
			(stroke
				(width 0.1524)
				(type default)
			)
			(layer "F.SilkS")
		)
		(fp_line
			(start 0.7874 -0.4064)
			(end 0.7874 0.4064)
			(stroke
				(width 0.1524)
				(type default)
			)
			(layer "F.SilkS")
		)
		(fp_line
			(start -0.7874 0.4064)
			(end -0.7874 -0.4064)
			(stroke
				(width 0.1524)
				(type default)
			)
			(layer "F.SilkS")
		)
		(fp_line
			(start -0.7874 -0.4064)
			(end 0.7874 -0.4064)
			(stroke
				(width 0.1524)
				(type default)
			)
			(layer "F.SilkS")
		)
		(fp_line
			(start 0.67945 0.3048)
			(end 0.120396 0.3048)
			(stroke
				(width 0.1)
				(type default)
			)
			(layer "F.Fab")
		)
		(fp_line
			(start 0.67945 -0.3048)
			(end 0.67945 0.3048)
			(stroke
				(width 0.1)
				(type default)
			)
			(layer "F.Fab")
		)
		(fp_line
			(start 0.12065 -0.2794)
			(end 0.12065 -0.3048)
			(stroke
				(width 0.1)
				(type default)
			)
			(layer "F.Fab")
		)
		(fp_line
			(start 0.12065 -0.3048)
			(end 0.67945 -0.3048)
			(stroke
				(width 0.1)
				(type default)
			)
			(layer "F.Fab")
		)
		(fp_line
			(start 0.120396 0.3048)
			(end 0.120396 0.2794)
			(stroke
				(width 0.1)
				(type default)
			)
			(layer "F.Fab")
		)
		(fp_line
			(start 0.120396 0.2794)
			(end -0.12065 0.2794)
			(stroke
				(width 0.1)
				(type default)
			)
			(layer "F.Fab")
		)
		(fp_line
			(start -0.12065 0.3048)
			(end -0.67945 0.3048)
			(stroke
				(width 0.1)
				(type default)
			)
			(layer "F.Fab")
		)
		(fp_line
			(start -0.12065 0.2794)
			(end -0.12065 0.3048)
			(stroke
				(width 0.1)
				(type default)
			)
			(layer "F.Fab")
		)
		(fp_line
			(start -0.12065 -0.2794)
			(end 0.12065 -0.2794)
			(stroke
				(width 0.1)
				(type default)
			)
			(layer "F.Fab")
		)
		(fp_line
			(start -0.12065 -0.305054)
			(end -0.12065 -0.2794)
			(stroke
				(width 0.1)
				(type default)
			)
			(layer "F.Fab")
		)
		(fp_line
			(start -0.67945 0.3048)
			(end -0.67945 -0.305054)
			(stroke
				(width 0.1)
				(type default)
			)
			(layer "F.Fab")
		)
		(fp_line
			(start -0.67945 -0.305054)
			(end -0.12065 -0.305054)
			(stroke
				(width 0.1)
				(type default)
			)
			(layer "F.Fab")
		)
		(pad "1" smd circle
			(at -0.40005 0 180)
			(size 0 0)
			(layers "F.Cu" "F.Mask" "F.Paste")
			(net "PVDD18_S5_P1")
		)
		(pad "2" smd circle
			(at 0.40005 0 180)
			(size 0 0)
			(layers "F.Cu" "F.Mask" "F.Paste")
			(net "SVID_PVDDCR_CPU0_P1_SVTO")
		)
	)
	(footprint ""
		(layer "F.Cu")
		(at 206.756 -99.695 180)
		(property "Reference" "R8038"
			(at 0 0 180)
			(layer "F.SilkS")
			(hide yes)
			(effects
				(font
					(size 1.27 1.27)
				)
			)
		)
		(property "Value" ""
			(at 0 0 180)
			(layer "F.Fab")
			(effects
				(font
					(size 1.27 1.27)
				)
			)
		)
		(duplicate_pad_numbers_are_jumpers no)
		(fp_line
			(start 0.7874 0.4064)
			(end -0.7874 0.4064)
			(stroke
				(width 0.1524)
				(type default)
			)
			(layer "F.SilkS")
		)
		(fp_line
			(start 0.7874 -0.4064)
			(end 0.7874 0.4064)
			(stroke
				(width 0.1524)
				(type default)
			)
			(layer "F.SilkS")
		)
		(fp_line
			(start -0.7874 0.4064)
			(end -0.7874 -0.4064)
			(stroke
				(width 0.1524)
				(type default)
			)
			(layer "F.SilkS")
		)
		(fp_line
			(start -0.7874 -0.4064)
			(end 0.7874 -0.4064)
			(stroke
				(width 0.1524)
				(type default)
			)
			(layer "F.SilkS")
		)
		(fp_line
			(start 0.67945 0.3048)
			(end 0.120396 0.3048)
			(stroke
				(width 0.1)
				(type default)
			)
			(layer "F.Fab")
		)
		(fp_line
			(start 0.67945 -0.3048)
			(end 0.67945 0.3048)
			(stroke
				(width 0.1)
				(type default)
			)
			(layer "F.Fab")
		)
		(fp_line
			(start 0.12065 -0.2794)
			(end 0.12065 -0.3048)
			(stroke
				(width 0.1)
				(type default)
			)
			(layer "F.Fab")
		)
		(fp_line
			(start 0.12065 -0.3048)
			(end 0.67945 -0.3048)
			(stroke
				(width 0.1)
				(type default)
			)
			(layer "F.Fab")
		)
		(fp_line
			(start 0.120396 0.3048)
			(end 0.120396 0.2794)
			(stroke
				(width 0.1)
				(type default)
			)
			(layer "F.Fab")
		)
		(fp_line
			(start 0.120396 0.2794)
			(end -0.12065 0.2794)
			(stroke
				(width 0.1)
				(type default)
			)
			(layer "F.Fab")
		)
		(fp_line
			(start -0.12065 0.3048)
			(end -0.67945 0.3048)
			(stroke
				(width 0.1)
				(type default)
			)
			(layer "F.Fab")
		)
		(fp_line
			(start -0.12065 0.2794)
			(end -0.12065 0.3048)
			(stroke
				(width 0.1)
				(type default)
			)
			(layer "F.Fab")
		)
		(fp_line
			(start -0.12065 -0.2794)
			(end 0.12065 -0.2794)
			(stroke
				(width 0.1)
				(type default)
			)
			(layer "F.Fab")
		)
		(fp_line
			(start -0.12065 -0.305054)
			(end -0.12065 -0.2794)
			(stroke
				(width 0.1)
				(type default)
			)
			(layer "F.Fab")
		)
		(fp_line
			(start -0.67945 0.3048)
			(end -0.67945 -0.305054)
			(stroke
				(width 0.1)
				(type default)
			)
			(layer "F.Fab")
		)
		(fp_line
			(start -0.67945 -0.305054)
			(end -0.12065 -0.305054)
			(stroke
				(width 0.1)
				(type default)
			)
			(layer "F.Fab")
		)
		(pad "1" smd circle
			(at -0.40005 0 180)
			(size 0 0)
			(layers "F.Cu" "F.Mask" "F.Paste")
			(net "P3V3_AUX")
		)
		(pad "2" smd circle
			(at 0.40005 0 180)
			(size 0 0)
			(layers "F.Cu" "F.Mask" "F.Paste")
			(net "PWRGD_CHGL_CPU0")
		)
	)
	(footprint ""
		(layer "F.Cu")
		(at 299.767498 -15.62481 180)
		(property "Reference" "R4204"
			(at 0 0 180)
			(layer "F.SilkS")
			(hide yes)
			(effects
				(font
					(size 1.27 1.27)
				)
			)
		)
		(property "Value" ""
			(at 0 0 180)
			(layer "F.Fab")
			(effects
				(font
					(size 1.27 1.27)
				)
			)
		)
		(duplicate_pad_numbers_are_jumpers no)
		(fp_line
			(start 0.7874 0.4064)
			(end -0.7874 0.4064)
			(stroke
				(width 0.1524)
				(type default)
			)
			(layer "F.SilkS")
		)
		(fp_line
			(start 0.7874 -0.4064)
			(end 0.7874 0.4064)
			(stroke
				(width 0.1524)
				(type default)
			)
			(layer "F.SilkS")
		)
		(fp_line
			(start -0.7874 0.4064)
			(end -0.7874 -0.4064)
			(stroke
				(width 0.1524)
				(type default)
			)
			(layer "F.SilkS")
		)
		(fp_line
			(start -0.7874 -0.4064)
			(end 0.7874 -0.4064)
			(stroke
				(width 0.1524)
				(type default)
			)
			(layer "F.SilkS")
		)
		(fp_line
			(start 0.67945 0.3048)
			(end 0.120396 0.3048)
			(stroke
				(width 0.1)
				(type default)
			)
			(layer "F.Fab")
		)
		(fp_line
			(start 0.67945 -0.3048)
			(end 0.67945 0.3048)
			(stroke
				(width 0.1)
				(type default)
			)
			(layer "F.Fab")
		)
		(fp_line
			(start 0.12065 -0.2794)
			(end 0.12065 -0.3048)
			(stroke
				(width 0.1)
				(type default)
			)
			(layer "F.Fab")
		)
		(fp_line
			(start 0.12065 -0.3048)
			(end 0.67945 -0.3048)
			(stroke
				(width 0.1)
				(type default)
			)
			(layer "F.Fab")
		)
		(fp_line
			(start 0.120396 0.3048)
			(end 0.120396 0.2794)
			(stroke
				(width 0.1)
				(type default)
			)
			(layer "F.Fab")
		)
		(fp_line
			(start 0.120396 0.2794)
			(end -0.12065 0.2794)
			(stroke
				(width 0.1)
				(type default)
			)
			(layer "F.Fab")
		)
		(fp_line
			(start -0.12065 0.3048)
			(end -0.67945 0.3048)
			(stroke
				(width 0.1)
				(type default)
			)
			(layer "F.Fab")
		)
		(fp_line
			(start -0.12065 0.2794)
			(end -0.12065 0.3048)
			(stroke
				(width 0.1)
				(type default)
			)
			(layer "F.Fab")
		)
		(fp_line
			(start -0.12065 -0.2794)
			(end 0.12065 -0.2794)
			(stroke
				(width 0.1)
				(type default)
			)
			(layer "F.Fab")
		)
		(fp_line
			(start -0.12065 -0.305054)
			(end -0.12065 -0.2794)
			(stroke
				(width 0.1)
				(type default)
			)
			(layer "F.Fab")
		)
		(fp_line
			(start -0.67945 0.3048)
			(end -0.67945 -0.305054)
			(stroke
				(width 0.1)
				(type default)
			)
			(layer "F.Fab")
		)
		(fp_line
			(start -0.67945 -0.305054)
			(end -0.12065 -0.305054)
			(stroke
				(width 0.1)
				(type default)
			)
			(layer "F.Fab")
		)
		(pad "1" smd circle
			(at -0.40005 0 180)
			(size 0 0)
			(layers "F.Cu" "F.Mask" "F.Paste")
			(net "P3V3_AUX")
		)
		(pad "2" smd circle
			(at 0.40005 0 180)
			(size 0 0)
			(layers "F.Cu" "F.Mask" "F.Paste")
			(net "U271_1_ADD0")
		)
	)
	(footprint ""
		(layer "F.Cu")
		(at 72.6948 -385.5212 90)
		(property "Reference" "R6714"
			(at 0 0 90)
			(layer "F.SilkS")
			(hide yes)
			(effects
				(font
					(size 1.27 1.27)
				)
			)
		)
		(property "Value" ""
			(at 0 0 90)
			(layer "F.Fab")
			(effects
				(font
					(size 1.27 1.27)
				)
			)
		)
		(duplicate_pad_numbers_are_jumpers no)
		(fp_line
			(start 0.32512 -0.175006)
			(end 0.32512 0.175006)
			(stroke
				(width 0.1)
				(type default)
			)
			(layer "F.Fab")
		)
		(fp_line
			(start -0.32512 -0.175006)
			(end 0.32512 -0.175006)
			(stroke
				(width 0.1)
				(type default)
			)
			(layer "F.Fab")
		)
		(fp_line
			(start 0.32512 0.175006)
			(end -0.32512 0.175006)
			(stroke
				(width 0.1)
				(type default)
			)
			(layer "F.Fab")
		)
		(fp_line
			(start -0.32512 0.175006)
			(end -0.32512 -0.175006)
			(stroke
				(width 0.1)
				(type default)
			)
			(layer "F.Fab")
		)
		(pad "1" smd rect
			(at -0.2667 0 90)
			(size 0.3048 0.381)
			(layers "F.Cu" "F.Mask" "F.Paste")
			(net "P1V8_CPU1_RT_1D")
		)
		(pad "2" smd rect
			(at 0.2667 0 270)
			(size 0.3048 0.381)
			(layers "F.Cu" "F.Mask" "F.Paste")
			(net "RT_CPU1_P0_ADDR2")
		)
	)
	(footprint ""
		(layer "F.Cu")
		(at 384.113278 -138.170158)
		(property "Reference" "PR599"
			(at 0 0 0)
			(layer "F.SilkS")
			(hide yes)
			(effects
				(font
					(size 1.27 1.27)
				)
			)
		)
		(property "Value" ""
			(at 0 0 0)
			(layer "F.Fab")
			(effects
				(font
					(size 1.27 1.27)
				)
			)
		)
		(duplicate_pad_numbers_are_jumpers no)
		(fp_line
			(start -0.7874 -0.4064)
			(end 0.7874 -0.4064)
			(stroke
				(width 0.1524)
				(type default)
			)
			(layer "F.SilkS")
		)
		(fp_line
			(start -0.7874 0.4064)
			(end -0.7874 -0.4064)
			(stroke
				(width 0.1524)
				(type default)
			)
			(layer "F.SilkS")
		)
		(fp_line
			(start 0.7874 -0.4064)
			(end 0.7874 0.4064)
			(stroke
				(width 0.1524)
				(type default)
			)
			(layer "F.SilkS")
		)
		(fp_line
			(start 0.7874 0.4064)
			(end -0.7874 0.4064)
			(stroke
				(width 0.1524)
				(type default)
			)
			(layer "F.SilkS")
		)
		(fp_line
			(start -0.67945 -0.305054)
			(end -0.12065 -0.305054)
			(stroke
				(width 0.1)
				(type default)
			)
			(layer "F.Fab")
		)
		(fp_line
			(start -0.67945 0.3048)
			(end -0.67945 -0.305054)
			(stroke
				(width 0.1)
				(type default)
			)
			(layer "F.Fab")
		)
		(fp_line
			(start -0.12065 -0.305054)
			(end -0.12065 -0.2794)
			(stroke
				(width 0.1)
				(type default)
			)
			(layer "F.Fab")
		)
		(fp_line
			(start -0.12065 -0.2794)
			(end 0.12065 -0.2794)
			(stroke
				(width 0.1)
				(type default)
			)
			(layer "F.Fab")
		)
		(fp_line
			(start -0.12065 0.2794)
			(end -0.12065 0.3048)
			(stroke
				(width 0.1)
				(type default)
			)
			(layer "F.Fab")
		)
		(fp_line
			(start -0.12065 0.3048)
			(end -0.67945 0.3048)
			(stroke
				(width 0.1)
				(type default)
			)
			(layer "F.Fab")
		)
		(fp_line
			(start 0.120396 0.2794)
			(end -0.12065 0.2794)
			(stroke
				(width 0.1)
				(type default)
			)
			(layer "F.Fab")
		)
		(fp_line
			(start 0.120396 0.3048)
			(end 0.120396 0.2794)
			(stroke
				(width 0.1)
				(type default)
			)
			(layer "F.Fab")
		)
		(fp_line
			(start 0.12065 -0.3048)
			(end 0.67945 -0.3048)
			(stroke
				(width 0.1)
				(type default)
			)
			(layer "F.Fab")
		)
		(fp_line
			(start 0.12065 -0.2794)
			(end 0.12065 -0.3048)
			(stroke
				(width 0.1)
				(type default)
			)
			(layer "F.Fab")
		)
		(fp_line
			(start 0.67945 -0.3048)
			(end 0.67945 0.3048)
			(stroke
				(width 0.1)
				(type default)
			)
			(layer "F.Fab")
		)
		(fp_line
			(start 0.67945 0.3048)
			(end 0.120396 0.3048)
			(stroke
				(width 0.1)
				(type default)
			)
			(layer "F.Fab")
		)
		(pad "1" smd circle
			(at -0.40005 0)
			(size 0 0)
			(layers "F.Cu" "F.Mask" "F.Paste")
			(net "PVDDCR_CPU0_P0_VINSEN")
		)
		(pad "2" smd circle
			(at 0.40005 0)
			(size 0 0)
			(layers "F.Cu" "F.Mask" "F.Paste")
			(net "GND")
		)
	)
	(footprint ""
		(layer "F.Cu")
		(at 399.53184 -381.41783 -90)
		(property "Reference" "C864"
			(at 0 0 270)
			(layer "F.SilkS")
			(hide yes)
			(effects
				(font
					(size 1.27 1.27)
				)
			)
		)
		(property "Value" ""
			(at 0 0 270)
			(layer "F.Fab")
			(effects
				(font
					(size 1.27 1.27)
				)
			)
		)
		(duplicate_pad_numbers_are_jumpers no)
		(fp_line
			(start -0.299974 0.150114)
			(end -0.299974 -0.150114)
			(stroke
				(width 0.1)
				(type default)
			)
			(layer "F.Fab")
		)
		(fp_line
			(start 0.299974 0.150114)
			(end -0.299974 0.150114)
			(stroke
				(width 0.1)
				(type default)
			)
			(layer "F.Fab")
		)
		(fp_line
			(start -0.299974 -0.150114)
			(end 0.299974 -0.150114)
			(stroke
				(width 0.1)
				(type default)
			)
			(layer "F.Fab")
		)
		(fp_line
			(start 0.299974 -0.150114)
			(end 0.299974 0.150114)
			(stroke
				(width 0.1)
				(type default)
			)
			(layer "F.Fab")
		)
		(pad "1" smd rect
			(at -0.2667 0 270)
			(size 0.3048 0.381)
			(layers "F.Cu" "F.Mask" "F.Paste")
			(net "P5E_CPU0_P2_TX_C_DN<2>")
		)
		(pad "2" smd rect
			(at 0.2667 0 270)
			(size 0.3048 0.381)
			(layers "F.Cu" "F.Mask" "F.Paste")
			(net "P5E_CPU0_P2_TX_DN<2>")
		)
	)
	(footprint ""
		(layer "F.Cu")
		(at 336.68462 -15.924276 90)
		(property "Reference" "D9"
			(at -2.94894 0.009652 90)
			(unlocked yes)
			(layer "F.SilkS")
			(effects
				(font
					(size 0.7874 0.5842)
					(thickness 0.1524)
				)
				(justify left)
			)
		)
		(property "Value" ""
			(at 0 0 90)
			(layer "F.Fab")
			(effects
				(font
					(size 1.27 1.27)
				)
			)
		)
		(duplicate_pad_numbers_are_jumpers no)
		(fp_line
			(start 1.16078 -0.4826)
			(end 1.16078 0.4826)
			(stroke
				(width 0.1524)
				(type default)
			)
			(layer "F.SilkS")
		)
		(fp_line
			(start 1.03378 -0.4826)
			(end 1.03378 0.4826)
			(stroke
				(width 0.1524)
				(type default)
			)
			(layer "F.SilkS")
		)
		(fp_line
			(start 0.90678 -0.4826)
			(end 0.90678 0.4826)
			(stroke
				(width 0.1524)
				(type default)
			)
			(layer "F.SilkS")
		)
		(fp_line
			(start -0.64008 -0.4826)
			(end 1.16078 -0.4826)
			(stroke
				(width 0.1524)
				(type default)
			)
			(layer "F.SilkS")
		)
		(fp_line
			(start -0.79248 -0.4826)
			(end 1.03378 -0.4826)
			(stroke
				(width 0.1524)
				(type default)
			)
			(layer "F.SilkS")
		)
		(fp_line
			(start -0.89408 -0.4826)
			(end 0.90678 -0.4826)
			(stroke
				(width 0.1524)
				(type default)
			)
			(layer "F.SilkS")
		)
		(fp_line
			(start 1.16078 0.4826)
			(end -0.64008 0.4826)
			(stroke
				(width 0.1524)
				(type default)
			)
			(layer "F.SilkS")
		)
		(fp_line
			(start 1.03378 0.4826)
			(end -0.79248 0.4826)
			(stroke
				(width 0.1524)
				(type default)
			)
			(layer "F.SilkS")
		)
		(fp_line
			(start 0.90678 0.4826)
			(end -0.90678 0.4826)
			(stroke
				(width 0.1524)
				(type default)
			)
			(layer "F.SilkS")
		)
		(fp_line
			(start -0.90678 0.4826)
			(end -0.90678 -0.4699)
			(stroke
				(width 0.1524)
				(type default)
			)
			(layer "F.SilkS")
		)
		(fp_line
			(start 0.499872 -0.249936)
			(end 0.499872 0.249936)
			(stroke
				(width 0.1)
				(type default)
			)
			(layer "F.Fab")
		)
		(fp_line
			(start -0.499872 -0.249936)
			(end 0.499872 -0.249936)
			(stroke
				(width 0.1)
				(type default)
			)
			(layer "F.Fab")
		)
		(fp_line
			(start 0.499872 0.249936)
			(end -0.499872 0.249936)
			(stroke
				(width 0.1)
				(type default)
			)
			(layer "F.Fab")
		)
		(fp_line
			(start -0.499872 0.249936)
			(end -0.499872 -0.249936)
			(stroke
				(width 0.1)
				(type default)
			)
			(layer "F.Fab")
		)
		(pad "A" smd rect
			(at -0.47498 0 90)
			(size 0.6096 0.7112)
			(layers "F.Cu" "F.Mask" "F.Paste")
			(net "LED_BIOS_DBG_MODE_R")
		)
		(pad "C" smd rect
			(at 0.47498 0 90)
			(size 0.6096 0.7112)
			(layers "F.Cu" "F.Mask" "F.Paste")
			(net "LED_BIOS_DBG_MODE")
		)
	)
)
